# T6G (Grand Teton) — schematic netlist excerpt (pin names and nets, part order shuffled) for the footprints in the layout excerpt that follows; sources: Cadence DE-HDL packaged netlist, KiCad conversion of 04192023_DAF0TMB3IC0_F0TG_MB_C_brd_V02_OCP.brd

PR3910  Q_RES  0 5% CHIP  pkg 0402LF  page 263 : A = HSC_VDD_R_1 ; B = HSC_VDD
C2039  Q_CAP  0.1UF 25V 10% X7R  pkg 0402  page 234 : A = P3V3_AUX_USB_HUB ; B = GND

(kicad_pcb
	(version 20260206)
	(generator "pcbnew")
	(generator_version "10.0")
	(general
		(thickness 1.6)
		(legacy_teardrops no)
	)
	(paper "A4")
	(title_block
		(title "04192023_DAF0TMB3IC0_F0TG_MB_C_brd_V02_OCP.brd")
		(comment 1 "Grand Teton / footprints 7876-7877 of 8354")
	)
	(layers
		(0 "F.Cu" signal "TOP")
		(4 "In1.Cu" signal "GND")
		(6 "In2.Cu" signal "IN1")
		(8 "In3.Cu" signal "GND1")
		(10 "In4.Cu" signal "IN2")
		(12 "In5.Cu" signal "GND2")
		(14 "In6.Cu" signal "IN3")
		(16 "In7.Cu" signal "GND3")
		(18 "In8.Cu" signal "VCC")
		(20 "In9.Cu" signal "VCC1")
		(22 "In10.Cu" signal "GND4")
		(24 "In11.Cu" signal "IN4")
		(26 "In12.Cu" signal "GND5")
		(28 "In13.Cu" signal "IN5")
		(30 "In14.Cu" signal "GND6")
		(32 "In15.Cu" signal "IN6")
		(34 "In16.Cu" signal "GND7")
		(2 "B.Cu" signal "BOTTOM")
		(9 "F.Adhes" user "F.Adhesive")
		(11 "B.Adhes" user "B.Adhesive")
		(13 "F.Paste" user "Package Geometry/Pastemask Top")
		(15 "B.Paste" user "Package Geometry/Pastemask Bottom")
		(5 "F.SilkS" user "Ref Des/Silkscreen Top")
		(7 "B.SilkS" user "Ref Des/Silkscreen Bottom")
		(1 "F.Mask" user "Board Geometry/Soldermask Top")
		(3 "B.Mask" user "Board Geometry/Soldermask Bottom")
		(17 "Dwgs.User" user "User.Drawings")
		(19 "Cmts.User" user "User.Comments")
		(21 "Eco1.User" user "User.Eco1")
		(23 "Eco2.User" user "User.Eco2")
		(25 "Edge.Cuts" user "Board Geometry/Outline")
		(27 "Margin" user)
		(31 "F.CrtYd" user "Package Geometry/Place Bound Top")
		(29 "B.CrtYd" user "Package Geometry/Place Bound Bottom")
		(35 "F.Fab" user "Ref Des/Assembly Top")
		(33 "B.Fab" user "Ref Des/Assembly Bottom")
	)
	(footprint ""
		(layer "B.Cu")
		(at 193.6369 -402.033232 -90)
		(property "Reference" "PR3910"
			(at 0 0 90)
			(layer "B.SilkS")
			(hide yes)
			(effects
				(font
					(size 1.27 1.27)
				)
				(justify mirror)
			)
		)
		(property "Value" ""
			(at 0 0 90)
			(layer "B.Fab")
			(effects
				(font
					(size 1.27 1.27)
				)
				(justify mirror)
			)
		)
		(duplicate_pad_numbers_are_jumpers no)
		(fp_line
			(start -0.7874 0.4064)
			(end 0.7874 0.4064)
			(stroke
				(width 0.1524)
				(type default)
			)
			(layer "B.SilkS")
		)
		(fp_line
			(start 0.7874 0.4064)
			(end 0.7874 -0.4064)
			(stroke
				(width 0.1524)
				(type default)
			)
			(layer "B.SilkS")
		)
		(fp_line
			(start -0.7874 -0.4064)
			(end -0.7874 0.4064)
			(stroke
				(width 0.1524)
				(type default)
			)
			(layer "B.SilkS")
		)
		(fp_line
			(start 0.7874 -0.4064)
			(end -0.7874 -0.4064)
			(stroke
				(width 0.1524)
				(type default)
			)
			(layer "B.SilkS")
		)
		(fp_line
			(start -0.67945 0.3048)
			(end -0.120396 0.3048)
			(stroke
				(width 0.1)
				(type default)
			)
			(layer "B.Fab")
		)
		(fp_line
			(start -0.120396 0.3048)
			(end -0.120396 0.2794)
			(stroke
				(width 0.1)
				(type default)
			)
			(layer "B.Fab")
		)
		(fp_line
			(start 0.12065 0.3048)
			(end 0.67945 0.3048)
			(stroke
				(width 0.1)
				(type default)
			)
			(layer "B.Fab")
		)
		(fp_line
			(start 0.67945 0.3048)
			(end 0.67945 -0.305054)
			(stroke
				(width 0.1)
				(type default)
			)
			(layer "B.Fab")
		)
		(fp_line
			(start -0.120396 0.2794)
			(end 0.12065 0.2794)
			(stroke
				(width 0.1)
				(type default)
			)
			(layer "B.Fab")
		)
		(fp_line
			(start 0.12065 0.2794)
			(end 0.12065 0.3048)
			(stroke
				(width 0.1)
				(type default)
			)
			(layer "B.Fab")
		)
		(fp_line
			(start -0.12065 -0.2794)
			(end -0.12065 -0.3048)
			(stroke
				(width 0.1)
				(type default)
			)
			(layer "B.Fab")
		)
		(fp_line
			(start 0.12065 -0.2794)
			(end -0.12065 -0.2794)
			(stroke
				(width 0.1)
				(type default)
			)
			(layer "B.Fab")
		)
		(fp_line
			(start -0.67945 -0.3048)
			(end -0.67945 0.3048)
			(stroke
				(width 0.1)
				(type default)
			)
			(layer "B.Fab")
		)
		(fp_line
			(start -0.12065 -0.3048)
			(end -0.67945 -0.3048)
			(stroke
				(width 0.1)
				(type default)
			)
			(layer "B.Fab")
		)
		(fp_line
			(start 0.12065 -0.305054)
			(end 0.12065 -0.2794)
			(stroke
				(width 0.1)
				(type default)
			)
			(layer "B.Fab")
		)
		(fp_line
			(start 0.67945 -0.305054)
			(end 0.12065 -0.305054)
			(stroke
				(width 0.1)
				(type default)
			)
			(layer "B.Fab")
		)
		(pad "1" smd circle
			(at 0.40005 0 90)
			(size 0 0)
			(layers "B.Cu" "B.Mask" "B.Paste")
			(net "HSC_VDD_R_1")
		)
		(pad "2" smd circle
			(at -0.40005 0 90)
			(size 0 0)
			(layers "B.Cu" "B.Mask" "B.Paste")
			(net "HSC_VDD")
		)
	)
	(footprint ""
		(layer "B.Cu")
		(at 16.610838 -97.314512 90)
		(property "Reference" "C2039"
			(at 0 0 90)
			(layer "B.SilkS")
			(hide yes)
			(effects
				(font
					(size 1.27 1.27)
				)
				(justify mirror)
			)
		)
		(property "Value" ""
			(at 0 0 90)
			(layer "B.Fab")
			(effects
				(font
					(size 1.27 1.27)
				)
				(justify mirror)
			)
		)
		(duplicate_pad_numbers_are_jumpers no)
		(fp_line
			(start 0.7874 -0.4064)
			(end -0.7874 -0.4064)
			(stroke
				(width 0.1524)
				(type default)
			)
			(layer "B.SilkS")
		)
		(fp_line
			(start -0.7874 -0.4064)
			(end -0.7874 0.4064)
			(stroke
				(width 0.1524)
				(type default)
			)
			(layer "B.SilkS")
		)
		(fp_line
			(start 0.7874 0.4064)
			(end 0.7874 -0.4064)
			(stroke
				(width 0.1524)
				(type default)
			)
			(layer "B.SilkS")
		)
		(fp_line
			(start -0.7874 0.4064)
			(end 0.7874 0.4064)
			(stroke
				(width 0.1524)
				(type default)
			)
			(layer "B.SilkS")
		)
		(fp_line
			(start 0.67945 -0.305054)
			(end 0.12065 -0.305054)
			(stroke
				(width 0.1)
				(type default)
			)
			(layer "B.Fab")
		)
		(fp_line
			(start 0.12065 -0.305054)
			(end 0.12065 -0.2794)
			(stroke
				(width 0.1)
				(type default)
			)
			(layer "B.Fab")
		)
		(fp_line
			(start -0.12065 -0.3048)
			(end -0.67945 -0.3048)
			(stroke
				(width 0.1)
				(type default)
			)
			(layer "B.Fab")
		)
		(fp_line
			(start -0.67945 -0.3048)
			(end -0.67945 0.3048)
			(stroke
				(width 0.1)
				(type default)
			)
			(layer "B.Fab")
		)
		(fp_line
			(start 0.12065 -0.2794)
			(end -0.12065 -0.2794)
			(stroke
				(width 0.1)
				(type default)
			)
			(layer "B.Fab")
		)
		(fp_line
			(start -0.12065 -0.2794)
			(end -0.12065 -0.3048)
			(stroke
				(width 0.1)
				(type default)
			)
			(layer "B.Fab")
		)
		(fp_line
			(start 0.12065 0.2794)
			(end 0.12065 0.3048)
			(stroke
				(width 0.1)
				(type default)
			)
			(layer "B.Fab")
		)
		(fp_line
			(start -0.120396 0.2794)
			(end 0.12065 0.2794)
			(stroke
				(width 0.1)
				(type default)
			)
			(layer "B.Fab")
		)
		(fp_line
			(start 0.67945 0.3048)
			(end 0.67945 -0.305054)
			(stroke
				(width 0.1)
				(type default)
			)
			(layer "B.Fab")
		)
		(fp_line
			(start 0.12065 0.3048)
			(end 0.67945 0.3048)
			(stroke
				(width 0.1)
				(type default)
			)
			(layer "B.Fab")
		)
		(fp_line
			(start -0.120396 0.3048)
			(end -0.120396 0.2794)
			(stroke
				(width 0.1)
				(type default)
			)
			(layer "B.Fab")
		)
		(fp_line
			(start -0.67945 0.3048)
			(end -0.120396 0.3048)
			(stroke
				(width 0.1)
				(type default)
			)
			(layer "B.Fab")
		)
		(pad "1" smd circle
			(at 0.40005 0 270)
			(size 0 0)
			(layers "B.Cu" "B.Mask" "B.Paste")
			(net "P3V3_AUX_USB_HUB")
		)
		(pad "2" smd circle
			(at -0.40005 0 270)
			(size 0 0)
			(layers "B.Cu" "B.Mask" "B.Paste")
			(net "GND")
		)
	)
)
